# SCM (Grand Teton) — schematic netlist excerpt (pin names and nets, part order shuffled) for the footprints in the layout excerpt that follows; sources: Cadence DE-HDL packaged netlist, KiCad conversion of 12092022_DA0F0TMDCD0_F0T_Management_Board_D_brd_V3_OCP.brd

C83  Q_CAP  0.1UF 25V 10% X7R  pkg 0402  page 16 : A = P3V3_RTC_AUX ; B = GND
L3  Q_INDUCTOR  BLM18PG121SN1D/2000MA IND  pkg SMLF  page 15 : \1\ = P1V8_AUX ; \2\ = P1V8_BMC_USB2AV18

(kicad_pcb
	(version 20260206)
	(generator "pcbnew")
	(generator_version "10.0")
	(general
		(thickness 1.6)
		(legacy_teardrops no)
	)
	(paper "A4")
	(title_block
		(title "12092022_DA0F0TMDCD0_F0T_Management_Board_D_brd_V3_OCP.brd")
		(comment 1 "Grand Teton / footprints 1430-1431 of 1440")
	)
	(layers
		(0 "F.Cu" signal "TOP")
		(4 "In1.Cu" signal "GND")
		(6 "In2.Cu" signal "IN1")
		(8 "In3.Cu" signal "GND1")
		(10 "In4.Cu" signal "IN2")
		(12 "In5.Cu" signal "VCC")
		(14 "In6.Cu" signal "VCC1")
		(16 "In7.Cu" signal "IN3")
		(18 "In8.Cu" signal "GND2")
		(20 "In9.Cu" signal "IN4")
		(22 "In10.Cu" signal "GND3")
		(2 "B.Cu" signal "BOTTOM")
		(9 "F.Adhes" user "F.Adhesive")
		(11 "B.Adhes" user "B.Adhesive")
		(13 "F.Paste" user "Package Geometry/Pastemask Top")
		(15 "B.Paste" user "Package Geometry/Pastemask Bottom")
		(5 "F.SilkS" user "Ref Des/Silkscreen Top")
		(7 "B.SilkS" user "Ref Des/Silkscreen Bottom")
		(1 "F.Mask" user "Board Geometry/Soldermask Top")
		(3 "B.Mask" user "Board Geometry/Soldermask Bottom")
		(17 "Dwgs.User" user "User.Drawings")
		(19 "Cmts.User" user "User.Comments")
		(21 "Eco1.User" user "User.Eco1")
		(23 "Eco2.User" user "User.Eco2")
		(25 "Edge.Cuts" user "Board Geometry/Outline")
		(27 "Margin" user)
		(31 "F.CrtYd" user "Package Geometry/Place Bound Top")
		(29 "B.CrtYd" user "Package Geometry/Place Bound Bottom")
		(35 "F.Fab" user "Ref Des/Assembly Top")
		(33 "B.Fab" user "Ref Des/Assembly Bottom")
	)
	(footprint ""
		(layer "B.Cu")
		(at 69.776848 -39.284402 180)
		(property "Reference" "L3"
			(at 0 0 0)
			(layer "B.SilkS")
			(hide yes)
			(effects
				(font
					(size 1.27 1.27)
				)
				(justify mirror)
			)
		)
		(property "Value" ""
			(at 0 0 0)
			(layer "B.Fab")
			(effects
				(font
					(size 1.27 1.27)
				)
				(justify mirror)
			)
		)
		(duplicate_pad_numbers_are_jumpers no)
		(fp_line
			(start 1.27 0.5842)
			(end 1.27 -0.5842)
			(stroke
				(width 0.1524)
				(type default)
			)
			(layer "B.SilkS")
		)
		(fp_line
			(start 1.27 -0.5588)
			(end 1.27 -0.5842)
			(stroke
				(width 0.1524)
				(type default)
			)
			(layer "B.SilkS")
		)
		(fp_line
			(start 1.27 -0.5842)
			(end -1.27 -0.5842)
			(stroke
				(width 0.1524)
				(type default)
			)
			(layer "B.SilkS")
		)
		(fp_line
			(start 0.127 0.5842)
			(end 0.127 -0.5842)
			(stroke
				(width 0.1524)
				(type default)
			)
			(layer "B.SilkS")
		)
		(fp_line
			(start -0.127 0.5842)
			(end -0.127 -0.5842)
			(stroke
				(width 0.1524)
				(type default)
			)
			(layer "B.SilkS")
		)
		(fp_line
			(start -1.27 0.5842)
			(end 1.27 0.5842)
			(stroke
				(width 0.1524)
				(type default)
			)
			(layer "B.SilkS")
		)
		(fp_line
			(start -1.27 0.5842)
			(end -1.27 -0.5842)
			(stroke
				(width 0.1524)
				(type default)
			)
			(layer "B.SilkS")
		)
		(fp_line
			(start 1.194308 0.406654)
			(end 1.194308 -0.406654)
			(stroke
				(width 0.1)
				(type default)
			)
			(layer "B.Fab")
		)
		(fp_line
			(start 1.194308 -0.406654)
			(end 0.9144 -0.406654)
			(stroke
				(width 0.1)
				(type default)
			)
			(layer "B.Fab")
		)
		(fp_line
			(start 0.9144 0.508)
			(end 0.9144 0.406654)
			(stroke
				(width 0.1)
				(type default)
			)
			(layer "B.Fab")
		)
		(fp_line
			(start 0.9144 0.406654)
			(end 1.194308 0.406654)
			(stroke
				(width 0.1)
				(type default)
			)
			(layer "B.Fab")
		)
		(fp_line
			(start 0.9144 -0.406654)
			(end 0.9144 -0.508)
			(stroke
				(width 0.1)
				(type default)
			)
			(layer "B.Fab")
		)
		(fp_line
			(start 0.9144 -0.508)
			(end -0.9144 -0.508)
			(stroke
				(width 0.1)
				(type default)
			)
			(layer "B.Fab")
		)
		(fp_line
			(start -0.9144 0.508)
			(end 0.9144 0.508)
			(stroke
				(width 0.1)
				(type default)
			)
			(layer "B.Fab")
		)
		(fp_line
			(start -0.9144 0.4064)
			(end -0.9144 0.508)
			(stroke
				(width 0.1)
				(type default)
			)
			(layer "B.Fab")
		)
		(fp_line
			(start -0.9144 -0.406654)
			(end -1.1938 -0.406654)
			(stroke
				(width 0.1)
				(type default)
			)
			(layer "B.Fab")
		)
		(fp_line
			(start -0.9144 -0.508)
			(end -0.9144 -0.406654)
			(stroke
				(width 0.1)
				(type default)
			)
			(layer "B.Fab")
		)
		(fp_line
			(start -1.1938 0.4064)
			(end -0.9144 0.4064)
			(stroke
				(width 0.1)
				(type default)
			)
			(layer "B.Fab")
		)
		(fp_line
			(start -1.1938 -0.406654)
			(end -1.1938 0.4064)
			(stroke
				(width 0.1)
				(type default)
			)
			(layer "B.Fab")
		)
		(pad "1" smd rect
			(at 0.7366 0 90)
			(size 0.7112 0.8128)
			(layers "B.Cu" "B.Mask" "B.Paste")
			(net "P1V8_AUX")
		)
		(pad "2" smd rect
			(at -0.7366 0 90)
			(size 0.7112 0.8128)
			(layers "B.Cu" "B.Mask" "B.Paste")
			(net "P1V8_BMC_USB2AV18")
		)
	)
	(footprint ""
		(layer "B.Cu")
		(at 46.111414 -53.754274 -90)
		(property "Reference" "C83"
			(at 0 0 90)
			(layer "B.SilkS")
			(hide yes)
			(effects
				(font
					(size 1.27 1.27)
				)
				(justify mirror)
			)
		)
		(property "Value" ""
			(at 0 0 90)
			(layer "B.Fab")
			(effects
				(font
					(size 1.27 1.27)
				)
				(justify mirror)
			)
		)
		(duplicate_pad_numbers_are_jumpers no)
		(fp_line
			(start -0.7874 0.4064)
			(end 0.7874 0.4064)
			(stroke
				(width 0.1524)
				(type default)
			)
			(layer "B.SilkS")
		)
		(fp_line
			(start 0.7874 0.4064)
			(end 0.7874 -0.4064)
			(stroke
				(width 0.1524)
				(type default)
			)
			(layer "B.SilkS")
		)
		(fp_line
			(start -0.7874 -0.4064)
			(end -0.7874 0.4064)
			(stroke
				(width 0.1524)
				(type default)
			)
			(layer "B.SilkS")
		)
		(fp_line
			(start 0.7874 -0.4064)
			(end -0.7874 -0.4064)
			(stroke
				(width 0.1524)
				(type default)
			)
			(layer "B.SilkS")
		)
		(fp_line
			(start -0.67945 0.3048)
			(end -0.120396 0.3048)
			(stroke
				(width 0.1)
				(type default)
			)
			(layer "B.Fab")
		)
		(fp_line
			(start -0.120396 0.3048)
			(end -0.120396 0.2794)
			(stroke
				(width 0.1)
				(type default)
			)
			(layer "B.Fab")
		)
		(fp_line
			(start 0.12065 0.3048)
			(end 0.67945 0.3048)
			(stroke
				(width 0.1)
				(type default)
			)
			(layer "B.Fab")
		)
		(fp_line
			(start 0.67945 0.3048)
			(end 0.67945 -0.305054)
			(stroke
				(width 0.1)
				(type default)
			)
			(layer "B.Fab")
		)
		(fp_line
			(start -0.120396 0.2794)
			(end 0.12065 0.2794)
			(stroke
				(width 0.1)
				(type default)
			)
			(layer "B.Fab")
		)
		(fp_line
			(start 0.12065 0.2794)
			(end 0.12065 0.3048)
			(stroke
				(width 0.1)
				(type default)
			)
			(layer "B.Fab")
		)
		(fp_line
			(start -0.12065 -0.2794)
			(end -0.12065 -0.3048)
			(stroke
				(width 0.1)
				(type default)
			)
			(layer "B.Fab")
		)
		(fp_line
			(start 0.12065 -0.2794)
			(end -0.12065 -0.2794)
			(stroke
				(width 0.1)
				(type default)
			)
			(layer "B.Fab")
		)
		(fp_line
			(start -0.67945 -0.3048)
			(end -0.67945 0.3048)
			(stroke
				(width 0.1)
				(type default)
			)
			(layer "B.Fab")
		)
		(fp_line
			(start -0.12065 -0.3048)
			(end -0.67945 -0.3048)
			(stroke
				(width 0.1)
				(type default)
			)
			(layer "B.Fab")
		)
		(fp_line
			(start 0.12065 -0.305054)
			(end 0.12065 -0.2794)
			(stroke
				(width 0.1)
				(type default)
			)
			(layer "B.Fab")
		)
		(fp_line
			(start 0.67945 -0.305054)
			(end 0.12065 -0.305054)
			(stroke
				(width 0.1)
				(type default)
			)
			(layer "B.Fab")
		)
		(pad "1" smd circle
			(at 0.40005 0 90)
			(size 0 0)
			(layers "B.Cu" "B.Mask" "B.Paste")
			(net "P3V3_RTC_AUX")
		)
		(pad "2" smd circle
			(at -0.40005 0 90)
			(size 0 0)
			(layers "B.Cu" "B.Mask" "B.Paste")
			(net "GND")
		)
	)
)
